FILE_TYPE = CONNECTIVITY;
{Allegro Design Entry HDL 17.4-2019 S026 (4007227) 1/17/2022}
"PAGE_NUMBER" = 102;
0"NC";
1"GND\g";
2"GND\g";
3"P3V3\g";
4"M_F_CPU1_SA_DQ<31:0>";
5"M_F_CPU1_SA_CB<7:0>";
6"M_F_CPU1_SB_CB<7:0>";
7"M_F_CPU1_SA_CA<6:0>";
8"M_F_CPU1_SB_CA<6:0>";
9"M_F_CPU1_SB_DQ<31:0>";
10"M_F_CPU1_SA_DQS_DN<9:0>";
11"M_F_CPU1_SA_DQS_DP<9:0>";
12"M_F_CPU1_SB_DQS_DP<9:0>";
13"M_F_CPU1_SB_DQS_DN<9:0>";
14"M_F_CPU1_SB_CB<1>";
15"P3V3_AUX\g";
16"PD_CHF_CPU1_DIMM_SAA";
17"I3C_SPD_DDRF_CPU1_SDA";
18"I3C_SPD_DDRAF_CPU1_SDA";
19"I3C_SPD_DDRAF_CPU1_SCL";
20"I3C_SPD_DDRF_CPU1_SCL";
21"GND\g";
22"GND\g";
23"GND\g";
24"P12V_MEM_CPU1\g";
25"PWRGD_CHF_CPU1_DIMM";
26"M_F_CPU1_ALERT_N";
27"M_F_CPU1_RESET_N";
28"M_F_CPU1_SB_CB<0>";
29"PWRGD_CHAF_CPU1";
30"M_F_CPU1_SB_RSP<0>";
31"M_F_CPU1_SA_RSP<0>";
32"M_F_CPU1_SA_DQ<14>";
33"M_F_CPU1_SA_DQ<13>";
34"M_F_CPU1_SA_DQ<12>";
35"M_F_CPU1_SA_DQ<11>";
36"M_F_CPU1_SA_DQ<10>";
37"M_F_CPU1_SA_DQ<20>";
38"M_F_CPU1_SA_DQ<19>";
39"M_F_CPU1_SA_DQ<18>";
40"M_F_CPU1_SB_DQS_DP<9>";
41"M_F_CPU1_SB_DQS_DN<9>";
42"M_F_CPU1_SA_DQS_DP<9>";
43"M_F_CPU1_SA_DQS_DN<9>";
44"M_F_CPU1_SA_DQS_DP<8>";
45"M_F_CPU1_SA_DQS_DN<8>";
46"M_F_CPU1_SB_DQS_DN<7>";
47"M_F_CPU1_SA_DQS_DP<7>";
48"M_F_CPU1_SB_DQS_DP<6>";
49"M_F_CPU1_SB_DQS_DN<6>";
50"M_F_CPU1_SA_DQS_DN<6>";
51"M_F_CPU1_SB_DQS_DP<5>";
52"M_F_CPU1_SB_DQS_DN<5>";
53"M_F_CPU1_SA_DQS_DP<5>";
54"M_F_CPU1_SA_DQS_DN<5>";
55"M_F_CPU1_SB_DQS_DP<4>";
56"M_F_CPU1_SB_DQS_DN<4>";
57"M_F_CPU1_SA_DQS_DP<4>";
58"M_F_CPU1_SA_DQS_DN<4>";
59"M_F_CPU1_SB_DQS_DP<3>";
60"M_F_CPU1_SB_DQS_DN<3>";
61"M_F_CPU1_SA_DQS_DP<3>";
62"M_F_CPU1_SA_DQS_DN<3>";
63"M_F_CPU1_SB_DQS_DP<2>";
64"M_F_CPU1_SB_DQS_DN<2>";
65"M_F_CPU1_SA_DQS_DP<2>";
66"M_F_CPU1_SA_DQS_DN<2>";
67"M_F_CPU1_SB_DQS_DP<1>";
68"M_F_CPU1_SB_DQS_DN<1>";
69"M_F_CPU1_SA_DQS_DP<1>";
70"M_F_CPU1_SA_DQS_DN<1>";
71"M_F_CPU1_SB_DQS_DP<0>";
72"M_F_CPU1_SB_DQS_DN<0>";
73"M_F_CPU1_SA_DQS_DP<0>";
74"M_F_CPU1_SA_DQS_DN<0>";
75"M_F_CPU1_SB_DQS_DP<7>";
76"M_F_CPU1_SB_DQS_DN<8>";
77"M_F_CPU1_SB_DQS_DP<8>";
78"M_F_CPU1_SA_DQS_DP<6>";
79"M_F_CPU1_SA_DQS_DN<7>";
80"M_F_CPU1_SB_PAR";
81"M_F_CPU1_SA_PAR";
82"M_F_CPU1_SB_DQ<0>";
83"M_F_CPU1_SB_DQ<1>";
84"M_F_CPU1_SB_DQ<2>";
85"M_F_CPU1_SB_DQ<3>";
86"M_F_CPU1_SB_DQ<4>";
87"M_F_CPU1_SB_DQ<5>";
88"M_F_CPU1_SB_DQ<6>";
89"M_F_CPU1_SB_DQ<7>";
90"M_F_CPU1_SB_DQ<8>";
91"M_F_CPU1_SB_DQ<9>";
92"M_F_CPU1_SB_DQ<10>";
93"M_F_CPU1_SB_DQ<11>";
94"M_F_CPU1_SB_DQ<12>";
95"M_F_CPU1_SB_DQ<13>";
96"M_F_CPU1_SB_DQ<14>";
97"M_F_CPU1_SB_DQ<15>";
98"M_F_CPU1_SB_DQ<16>";
99"M_F_CPU1_SB_DQ<17>";
100"M_F_CPU1_SB_DQ<18>";
101"M_F_CPU1_SB_DQ<19>";
102"M_F_CPU1_SB_DQ<20>";
103"M_F_CPU1_SB_DQ<21>";
104"M_F_CPU1_SB_DQ<22>";
105"M_F_CPU1_SB_DQ<23>";
106"M_F_CPU1_SB_DQ<24>";
107"M_F_CPU1_SB_DQ<25>";
108"M_F_CPU1_SB_DQ<26>";
109"M_F_CPU1_SB_DQ<27>";
110"M_F_CPU1_SB_DQ<28>";
111"M_F_CPU1_SB_DQ<29>";
112"M_F_CPU1_SB_DQ<30>";
113"M_F_CPU1_SB_DQ<31>";
114"M_F_CPU1_SA_DQ<0>";
115"M_F_CPU1_SA_DQ<1>";
116"M_F_CPU1_SA_DQ<2>";
117"M_F_CPU1_SA_DQ<3>";
118"M_F_CPU1_SA_DQ<4>";
119"M_F_CPU1_SA_DQ<5>";
120"M_F_CPU1_SA_DQ<6>";
121"M_F_CPU1_SA_DQ<7>";
122"M_F_CPU1_SA_DQ<8>";
123"M_F_CPU1_SA_DQ<9>";
124"M_F_CPU1_SA_DQ<15>";
125"M_F_CPU1_SA_DQ<16>";
126"M_F_CPU1_SA_DQ<17>";
127"M_F_CPU1_SA_DQ<21>";
128"M_F_CPU1_SA_DQ<22>";
129"M_F_CPU1_SA_DQ<23>";
130"M_F_CPU1_SA_DQ<24>";
131"M_F_CPU1_SA_DQ<25>";
132"M_F_CPU1_SA_DQ<26>";
133"M_F_CPU1_SA_DQ<27>";
134"M_F_CPU1_SA_DQ<28>";
135"M_F_CPU1_SA_DQ<29>";
136"M_F_CPU1_SA_DQ<30>";
137"M_F_CPU1_SB_CS_N<1>";
138"M_F_CPU1_SA_CS_N<1>";
139"M_F_CPU1_SB_CS_N<0>";
140"M_F_CPU1_SA_CS_N<0>";
141"M_F_CPU1_CLK_DP<0>";
142"M_F_CPU1_CLK_DN<0>";
143"M_F_CPU1_SB_CB<2>";
144"M_F_CPU1_SB_CB<3>";
145"M_F_CPU1_SB_CB<4>";
146"M_F_CPU1_SB_CB<5>";
147"M_F_CPU1_SB_CB<6>";
148"M_F_CPU1_SA_CB<0>";
149"M_F_CPU1_SA_CB<2>";
150"M_F_CPU1_SA_CB<3>";
151"M_F_CPU1_SA_CB<5>";
152"M_F_CPU1_SA_CB<6>";
153"M_F_CPU1_SB_CA<6>";
154"M_F_CPU1_SA_CA<6>";
155"M_F_CPU1_SB_CA<5>";
156"M_F_CPU1_SA_CA<5>";
157"M_F_CPU1_SB_CA<4>";
158"M_F_CPU1_SA_CA<4>";
159"M_F_CPU1_SB_CA<3>";
160"M_F_CPU1_SA_CA<3>";
161"M_F_CPU1_SB_CA<2>";
162"M_F_CPU1_SA_CA<2>";
163"M_F_CPU1_SB_CA<1>";
164"M_F_CPU1_SA_CA<1>";
165"M_F_CPU1_SB_CA<0>";
166"M_F_CPU1_SA_CA<0>";
167"M_F_CPU1_SB_CB<7>";
168"M_F_CPU1_SA_CB<1>";
169"M_F_CPU1_SA_CB<4>";
170"M_F_CPU1_SA_CB<7>";
171"M_F_CPU1_SA_DQ<31>";
172"PD_CHF_CPU1_DIMM_SAA";
%"TAP"
"1","(-6125,4325)","0","mstr_standard","I100";
;
CDS_LIB"mstr_standard"
BODY_TYPE"PLUMBING"
HDL_TAP"TRUE";
"B \NAC \NWC"4;
"S \NAC"
BN"7"121;
%"TAP"
"1","(-6125,4275)","0","mstr_standard","I101";
;
CDS_LIB"mstr_standard"
BODY_TYPE"PLUMBING"
HDL_TAP"TRUE";
"B \NAC \NWC"4;
"S \NAC"
BN"6"120;
%"TAP"
"1","(-6125,4375)","0","mstr_standard","I102";
;
CDS_LIB"mstr_standard"
BODY_TYPE"PLUMBING"
HDL_TAP"TRUE";
"B \NAC \NWC"4;
"S \NAC"
BN"8"122;
%"TAP"
"1","(-6125,4425)","0","mstr_standard","I103";
;
CDS_LIB"mstr_standard"
BODY_TYPE"PLUMBING"
HDL_TAP"TRUE";
"B \NAC \NWC"4;
"S \NAC"
BN"9"123;
%"TAP"
"1","(-6125,4525)","0","mstr_standard","I104";
;
CDS_LIB"mstr_standard"
BODY_TYPE"PLUMBING"
HDL_TAP"TRUE";
"B \NAC \NWC"4;
"S \NAC"
BN"11"35;
%"TAP"
"1","(-6125,4575)","0","mstr_standard","I105";
;
CDS_LIB"mstr_standard"
BODY_TYPE"PLUMBING"
HDL_TAP"TRUE";
"B \NAC \NWC"4;
"S \NAC"
BN"12"34;
%"TAP"
"1","(-6125,4625)","0","mstr_standard","I106";
;
CDS_LIB"mstr_standard"
BODY_TYPE"PLUMBING"
HDL_TAP"TRUE";
"B \NAC \NWC"4;
"S \NAC"
BN"13"33;
%"TAP"
"1","(-6125,4675)","0","mstr_standard","I107";
;
CDS_LIB"mstr_standard"
BODY_TYPE"PLUMBING"
HDL_TAP"TRUE";
"B \NAC \NWC"4;
"S \NAC"
BN"14"32;
%"TAP"
"1","(-6125,4475)","0","mstr_standard","I108";
;
CDS_LIB"mstr_standard"
BODY_TYPE"PLUMBING"
HDL_TAP"TRUE";
"B \NAC \NWC"4;
"S \NAC"
BN"10"36;
%"TAP"
"1","(-6125,4925)","0","mstr_standard","I109";
;
CDS_LIB"mstr_standard"
BODY_TYPE"PLUMBING"
HDL_TAP"TRUE";
"B \NAC \NWC"4;
"S \NAC"
BN"19"38;
%"TAP"
"1","(-6125,4775)","0","mstr_standard","I110";
;
CDS_LIB"mstr_standard"
BODY_TYPE"PLUMBING"
HDL_TAP"TRUE";
"B \NAC \NWC"4;
"S \NAC"
BN"16"125;
%"TAP"
"1","(-6125,4875)","0","mstr_standard","I111";
;
CDS_LIB"mstr_standard"
BODY_TYPE"PLUMBING"
HDL_TAP"TRUE";
"B \NAC \NWC"4;
"S \NAC"
BN"18"39;
%"TAP"
"1","(-6125,4825)","0","mstr_standard","I112";
;
CDS_LIB"mstr_standard"
BODY_TYPE"PLUMBING"
HDL_TAP"TRUE";
"B \NAC \NWC"4;
"S \NAC"
BN"17"126;
%"TAP"
"1","(-6125,4725)","0","mstr_standard","I113";
;
CDS_LIB"mstr_standard"
BODY_TYPE"PLUMBING"
HDL_TAP"TRUE";
"B \NAC \NWC"4;
"S \NAC"
BN"15"124;
%"TAP"
"1","(-6125,4975)","0","mstr_standard","I114";
;
CDS_LIB"mstr_standard"
BODY_TYPE"PLUMBING"
HDL_TAP"TRUE";
"B \NAC \NWC"4;
"S \NAC"
BN"20"37;
%"TAP"
"1","(-6125,5025)","0","mstr_standard","I115";
;
CDS_LIB"mstr_standard"
BODY_TYPE"PLUMBING"
HDL_TAP"TRUE";
"B \NAC \NWC"4;
"S \NAC"
BN"21"127;
%"TAP"
"1","(-6125,5075)","0","mstr_standard","I116";
;
CDS_LIB"mstr_standard"
BODY_TYPE"PLUMBING"
HDL_TAP"TRUE";
"B \NAC \NWC"4;
"S \NAC"
BN"22"128;
%"TAP"
"1","(-6125,5225)","0","mstr_standard","I117";
;
CDS_LIB"mstr_standard"
BODY_TYPE"PLUMBING"
HDL_TAP"TRUE";
"B \NAC \NWC"4;
"S \NAC"
BN"25"131;
%"TAP"
"1","(-6125,5125)","0","mstr_standard","I118";
;
CDS_LIB"mstr_standard"
BODY_TYPE"PLUMBING"
HDL_TAP"TRUE";
"B \NAC \NWC"4;
"S \NAC"
BN"23"129;
%"TAP"
"1","(-6125,5175)","0","mstr_standard","I119";
;
CDS_LIB"mstr_standard"
BODY_TYPE"PLUMBING"
HDL_TAP"TRUE";
"B \NAC \NWC"4;
"S \NAC"
BN"24"130;
%"TAP"
"1","(-6125,5425)","0","mstr_standard","I120";
;
CDS_LIB"mstr_standard"
BODY_TYPE"PLUMBING"
HDL_TAP"TRUE";
"B \NAC \NWC"4;
"S \NAC"
BN"29"135;
%"TAP"
"1","(-6125,5475)","0","mstr_standard","I121";
;
CDS_LIB"mstr_standard"
BODY_TYPE"PLUMBING"
HDL_TAP"TRUE";
"B \NAC \NWC"4;
"S \NAC"
BN"30"136;
%"TAP"
"1","(-6125,5375)","0","mstr_standard","I122";
;
CDS_LIB"mstr_standard"
BODY_TYPE"PLUMBING"
HDL_TAP"TRUE";
"B \NAC \NWC"4;
"S \NAC"
BN"28"134;
%"TAP"
"1","(-6125,5325)","0","mstr_standard","I123";
;
CDS_LIB"mstr_standard"
BODY_TYPE"PLUMBING"
HDL_TAP"TRUE";
"B \NAC \NWC"4;
"S \NAC"
BN"27"133;
%"TAP"
"1","(-6125,5275)","0","mstr_standard","I124";
;
CDS_LIB"mstr_standard"
BODY_TYPE"PLUMBING"
HDL_TAP"TRUE";
"B \NAC \NWC"4;
"S \NAC"
BN"26"132;
%"TAP"
"1","(-6125,5525)","0","mstr_standard","I125";
;
CDS_LIB"mstr_standard"
BODY_TYPE"PLUMBING"
HDL_TAP"TRUE";
"B \NAC \NWC"4;
"S \NAC"
BN"31"171;
%"GND"
"1","(-6550,1050)","0","mstr_symbols","I128";
;
SIZE"1B"
CDS_LIB"mstr_symbols"
BOM_COST"MEM"
VOLTAGE"0.0"
BODY_TYPE"PLUMBING"
HDL_POWER"GND";
"A\NAC"1;
%"Q_RES"
"2","(-6550,1275)","0","pure_quanta","I129";
;
LOCATION"R773"
$SEC"1"
CDS_SEC"1"
WATTAGE"1/16W"
MATERIAL"CHIP"
TOLERANCE"1%"
VALUE"84.5K"
PACK_TYPE"0402LF"
CDS_LIB"pure_quanta"
PART_NUMBER"CS38452FB05";
"A"
$PN"1"172;
"B"
$PN"2"1;
%"GND"
"1","(-2200,2000)","0","mstr_symbols","I140";
;
SIZE"1B"
CDS_LIB"mstr_symbols"
VOLTAGE"0.0"
BODY_TYPE"PLUMBING"
HDL_POWER"GND";
"A\NAC"21;
%"GND"
"1","(-400,1775)","0","mstr_symbols","I141";
;
CDS_LIB"mstr_symbols"
SIZE"1B"
VOLTAGE"0.0"
BODY_TYPE"PLUMBING"
HDL_POWER"GND";
"A\NAC"22;
%"SCONN288_DDR506112002KQ"
"3","(-1300,3775)","0","pure_quanta","I142";
;
LOCATION"J33"
$SEC"3"
CDS_SEC"3"
PART_TYPE"SMLF"
VALUE"SCONN288_DDR506112002KQ"
MATERIAL"IO"
CDS_LMAN_SYM_OUTLINE"-450,1800,450,-1750"
NEEDS_NO_SIZE"TRUE"
CDS_LIB"pure_quanta"
PART_NUMBER"DFHST8FS479";
"G3"
$PN"G3"22;
"G2"
$PN"G2"22;
"G1"
$PN"G1"22;
"VSS62"
$PN"141"22;
"VSS61"
$PN"139"22;
"VSS60"
$PN"136"22;
"VSS58"
$PN"132"22;
"VSS104"
$PN"240"21;
"VSS102"
$PN"235"21;
"VSS100"
$PN"230"21;
"VIN_BULK2"
$PN"146"24;
"VIN_BULK1"
$PN"145"24;
"VIN_BULK0"
$PN"1"24;
"VSS126"
$PN"288"21;
"VSS125"
$PN"286"21;
"VSS124"
$PN"284"21;
"VSS123"
$PN"281"21;
"VSS122"
$PN"279"21;
"VSS121"
$PN"277"21;
"VSS120"
$PN"275"21;
"VSS119"
$PN"273"21;
"VSS118"
$PN"270"21;
"VSS117"
$PN"268"21;
"VSS116"
$PN"266"21;
"VSS115"
$PN"264"21;
"VSS114"
$PN"262"21;
"VSS113"
$PN"259"21;
"VSS112"
$PN"257"21;
"VSS111"
$PN"255"21;
"VSS110"
$PN"253"21;
"VSS109"
$PN"251"21;
"VSS108"
$PN"248"21;
"VSS107"
$PN"246"21;
"VSS106"
$PN"244"21;
"VSS105"
$PN"242"21;
"VSS103"
$PN"237"21;
"VSS101"
$PN"233"21;
"VSS99"
$PN"228"21;
"VSS98"
$PN"226"21;
"VSS97"
$PN"224"21;
"VSS96"
$PN"222"21;
"VSS95"
$PN"219"21;
"VSS94"
$PN"216"21;
"VSS93"
$PN"214"21;
"VSS92"
$PN"212"21;
"VSS91"
$PN"210"21;
"VSS90"
$PN"208"21;
"VSS89"
$PN"206"21;
"VSS88"
$PN"204"21;
"VSS87"
$PN"202"21;
"VSS86"
$PN"199"21;
"VSS85"
$PN"197"21;
"VSS84"
$PN"195"21;
"VSS83"
$PN"193"21;
"VSS82"
$PN"191"21;
"VSS81"
$PN"188"21;
"VSS80"
$PN"186"21;
"VSS79"
$PN"184"21;
"VSS78"
$PN"182"21;
"VSS77"
$PN"180"21;
"VSS76"
$PN"177"21;
"VSS75"
$PN"175"21;
"VSS74"
$PN"173"21;
"VSS73"
$PN"171"21;
"VSS72"
$PN"169"21;
"VSS71"
$PN"166"21;
"VSS70"
$PN"164"21;
"VSS69"
$PN"162"21;
"VSS68"
$PN"160"21;
"VSS67"
$PN"158"21;
"VSS66"
$PN"155"21;
"VSS65"
$PN"153"21;
"VSS64"
$PN"151"21;
"VSS63"
$PN"143"22;
"VSS59"
$PN"134"22;
"VSS57"
$PN"130"22;
"VSS56"
$PN"128"22;
"VSS55"
$PN"125"22;
"VSS54"
$PN"123"22;
"VSS53"
$PN"121"22;
"VSS52"
$PN"119"22;
"VSS51"
$PN"117"22;
"VSS50"
$PN"114"22;
"VSS49"
$PN"112"22;
"VSS48"
$PN"110"22;
"VSS47"
$PN"108"22;
"VSS46"
$PN"106"22;
"VSS45"
$PN"103"22;
"VSS44"
$PN"101"22;
"VSS43"
$PN"99"22;
"VSS42"
$PN"97"22;
"VSS41"
$PN"95"22;
"VSS40"
$PN"92"22;
"VSS39"
$PN"90"22;
"VSS38"
$PN"88"22;
"VSS37"
$PN"85"22;
"VSS36"
$PN"83"22;
"VSS35"
$PN"81"22;
"VSS34"
$PN"79"22;
"VSS33"
$PN"77"22;
"VSS32"
$PN"75"22;
"VSS31"
$PN"73"22;
"VSS30"
$PN"71"22;
"VSS29"
$PN"69"22;
"VSS28"
$PN"67"22;
"VSS27"
$PN"65"22;
"VSS26"
$PN"63"22;
"VSS25"
$PN"61"22;
"VSS24"
$PN"59"22;
"VSS23"
$PN"57"22;
"VSS22"
$PN"54"22;
"VSS21"
$PN"52"22;
"VSS20"
$PN"50"22;
"VSS19"
$PN"48"22;
"VSS18"
$PN"46"22;
"VSS17"
$PN"43"22;
"VSS16"
$PN"41"22;
"VSS15"
$PN"39"22;
"VSS14"
$PN"37"22;
"VSS13"
$PN"35"22;
"VSS12"
$PN"32"22;
"VSS11"
$PN"30"22;
"VSS10"
$PN"28"22;
"VSS9"
$PN"26"22;
"VSS8"
$PN"24"22;
"VSS7"
$PN"21"22;
"VSS6"
$PN"19"22;
"VSS5"
$PN"17"22;
"VSS4"
$PN"15"22;
"VSS3"
$PN"13"22;
"VSS2"
$PN"10"22;
"VSS1"
$PN"8"22;
"VSS0"
$PN"6"22;
%"Q_CAP"
"1","(-8675,3350)","2","pure_quanta","I185";
;
LOCATION"C156"
$SEC"1"
CDS_SEC"1"
PACK_TYPE"0402"
VALUE"0.1UF"
MATERIAL"X7R"
VOLTAGE"25V"
TOLERANCE"10%"
CDS_LIB"pure_quanta"
BOM_COST"MEM"
ROOM""
PART_NUMBER"CH4104K1B00";
"B"
$PN"2"2;
"A"
$PN"1"15;
%"GND"
"1","(-8675,3125)","0","mstr_symbols","I186";
;
BOM_COST"MEM"
SIZE"1B"
CDS_LIB"mstr_symbols"
VOLTAGE"0"
ROOM"MEM_EFGH_DECOUPLING_CAPS"
BODY_TYPE"PLUMBING"
HDL_POWER"GND";
"A\NAC"2;
%"Q_RES"
"1","(-8600,2275)","2","pure_quanta","I188";
;
LOCATION"R1183"
$SEC"1"
CDS_SEC"1"
VALUE"1K"
TOLERANCE"1%"
BOM_COST"MEM"
CDS_LIB"pure_quanta"
WATTAGE"1/16W"
MATERIAL"CHIP"
PACK_TYPE"0402LF"
ROOM""
PART_NUMBER"CS21002FB06";
"B"
$PN"2"29;
"A"
$PN"1"25;
%"VCC_CORE"
"1","(-8475,2600)","0","mstr_symbols","I189";
;
HDL_POWER"P3V3"
CDS_LIB"mstr_symbols"
VOLTAGE"3.3"
ROOM"PVCCINFAON_CPU0_CTRL";
"A"3;
%"Q_RES"
"2","(-8475,2425)","0","pure_quanta","I190";
;
LOCATION"R108"
$SEC"1"
CDS_SEC"1"
PACK_TYPE"0402LF"
MATERIAL"EMPTY"
WATTAGE"1/16W"
TOLERANCE"1%"
VALUE"1K"
CDS_LIB"pure_quanta"
BOM_COST"MEM"
ROOM""
PART_NUMBER"CS21002FB06";
"A"
$PN"1"3;
"B"
$PN"2"25;
%"TAP"
"1","(-3500,4000)","0","mstr_standard","I191";
;
CDS_LIB"mstr_standard"
BODY_TYPE"PLUMBING"
HDL_TAP"TRUE";
"B \NAC \NWC"11;
"S \NAC"
BN"2"65;
%"TAP"
"1","(-3500,4200)","0","mstr_standard","I193";
;
CDS_LIB"mstr_standard"
BODY_TYPE"PLUMBING"
HDL_TAP"TRUE";
"B \NAC \NWC"11;
"S \NAC"
BN"4"57;
%"TAP"
"1","(-3300,4650)","0","mstr_standard","I198";
;
CDS_LIB"mstr_standard"
BODY_TYPE"PLUMBING"
HDL_TAP"TRUE";
"B \NAC \NWC"10;
"S \NAC"
BN"9"43;
%"TAP"
"1","(-3300,4550)","0","mstr_standard","I199";
;
CDS_LIB"mstr_standard"
BODY_TYPE"PLUMBING"
HDL_TAP"TRUE";
"B \NAC \NWC"10;
"S \NAC"
BN"8"45;
%"TAP"
"1","(-3300,4450)","0","mstr_standard","I200";
;
CDS_LIB"mstr_standard"
BODY_TYPE"PLUMBING"
HDL_TAP"TRUE";
"B \NAC \NWC"10;
"S \NAC"
BN"7"79;
%"TAP"
"1","(-3500,4700)","0","mstr_standard","I201";
;
CDS_LIB"mstr_standard"
BODY_TYPE"PLUMBING"
HDL_TAP"TRUE";
"B \NAC \NWC"11;
"S \NAC"
BN"9"42;
%"TAP"
"1","(-3500,4600)","0","mstr_standard","I202";
;
CDS_LIB"mstr_standard"
BODY_TYPE"PLUMBING"
HDL_TAP"TRUE";
"B \NAC \NWC"11;
"S \NAC"
BN"8"44;
%"TAP"
"1","(-3500,4400)","0","mstr_standard","I203";
;
CDS_LIB"mstr_standard"
BODY_TYPE"PLUMBING"
HDL_TAP"TRUE";
"B \NAC \NWC"11;
"S \NAC"
BN"6"78;
%"TAP"
"1","(-3500,4500)","0","mstr_standard","I204";
;
CDS_LIB"mstr_standard"
BODY_TYPE"PLUMBING"
HDL_TAP"TRUE";
"B \NAC \NWC"11;
"S \NAC"
BN"7"47;
%"TAP"
"1","(-3300,4350)","0","mstr_standard","I205";
;
CDS_LIB"mstr_standard"
BODY_TYPE"PLUMBING"
HDL_TAP"TRUE";
"B \NAC \NWC"10;
"S \NAC"
BN"6"50;
%"TAP"
"1","(-3300,4250)","0","mstr_standard","I206";
;
CDS_LIB"mstr_standard"
BODY_TYPE"PLUMBING"
HDL_TAP"TRUE";
"B \NAC \NWC"10;
"S \NAC"
BN"5"54;
%"TAP"
"1","(-3300,4150)","0","mstr_standard","I207";
;
CDS_LIB"mstr_standard"
BODY_TYPE"PLUMBING"
HDL_TAP"TRUE";
"B \NAC \NWC"10;
"S \NAC"
BN"4"58;
%"TAP"
"1","(-3300,4050)","0","mstr_standard","I208";
;
CDS_LIB"mstr_standard"
BODY_TYPE"PLUMBING"
HDL_TAP"TRUE";
"B \NAC \NWC"10;
"S \NAC"
BN"3"62;
%"TAP"
"1","(-3300,3950)","0","mstr_standard","I209";
;
CDS_LIB"mstr_standard"
BODY_TYPE"PLUMBING"
HDL_TAP"TRUE";
"B \NAC \NWC"10;
"S \NAC"
BN"2"66;
%"TAP"
"1","(-3500,4300)","0","mstr_standard","I210";
;
CDS_LIB"mstr_standard"
BODY_TYPE"PLUMBING"
HDL_TAP"TRUE";
"B \NAC \NWC"11;
"S \NAC"
BN"5"53;
%"TAP"
"1","(-3500,3900)","0","mstr_standard","I211";
;
CDS_LIB"mstr_standard"
BODY_TYPE"PLUMBING"
HDL_TAP"TRUE";
"B \NAC \NWC"11;
"S \NAC"
BN"1"69;
%"TAP"
"1","(-3500,4100)","0","mstr_standard","I212";
;
CDS_LIB"mstr_standard"
BODY_TYPE"PLUMBING"
HDL_TAP"TRUE";
"B \NAC \NWC"11;
"S \NAC"
BN"3"61;
%"TAP"
"1","(-3300,3750)","0","mstr_standard","I213";
;
CDS_LIB"mstr_standard"
BODY_TYPE"PLUMBING"
HDL_TAP"TRUE";
"B \NAC \NWC"10;
"S \NAC"
BN"0"74;
%"TAP"
"1","(-3300,3850)","0","mstr_standard","I214";
;
CDS_LIB"mstr_standard"
BODY_TYPE"PLUMBING"
HDL_TAP"TRUE";
"B \NAC \NWC"10;
"S \NAC"
BN"1"70;
%"TAP"
"1","(-3300,3600)","0","mstr_standard","I215";
;
CDS_LIB"mstr_standard"
BODY_TYPE"PLUMBING"
HDL_TAP"TRUE";
"B \NAC \NWC"13;
"S \NAC"
BN"9"41;
%"TAP"
"1","(-3300,3500)","0","mstr_standard","I216";
;
CDS_LIB"mstr_standard"
BODY_TYPE"PLUMBING"
HDL_TAP"TRUE";
"B \NAC \NWC"13;
"S \NAC"
BN"8"76;
%"TAP"
"1","(-3300,3400)","0","mstr_standard","I217";
;
CDS_LIB"mstr_standard"
BODY_TYPE"PLUMBING"
HDL_TAP"TRUE";
"B \NAC \NWC"13;
"S \NAC"
BN"7"46;
%"TAP"
"1","(-3500,3650)","0","mstr_standard","I218";
;
CDS_LIB"mstr_standard"
BODY_TYPE"PLUMBING"
HDL_TAP"TRUE";
"B \NAC \NWC"12;
"S \NAC"
BN"9"40;
%"TAP"
"1","(-3500,3800)","0","mstr_standard","I219";
;
CDS_LIB"mstr_standard"
BODY_TYPE"PLUMBING"
HDL_TAP"TRUE";
"B \NAC \NWC"11;
"S \NAC"
BN"0"73;
%"SCONN288_DDR506112002KQ"
"1","(-6975,3775)","0","pure_quanta","I22";
;
LOCATION"J33"
$SEC"1"
CDS_SEC"1"
PART_TYPE"SMLF"
VALUE"SCONN288_DDR506112002KQ"
MATERIAL"IO"
CDS_LMAN_SYM_OUTLINE"-450,1900,450,-1850"
NEEDS_NO_SIZE"TRUE"
CDS_LIB"pure_quanta"
PART_NUMBER"DFHST8FS479";
"PWR_GOOD||FAIL_N"
$PN"147"25;
"DQ31_A"
$PN"194"171;
"CB7_A"
$PN"205"170;
"CB4_A"
$PN"58"169;
"CB1_A"
$PN"53"168;
"CB7_B"
$PN"236"167;
"ALERT_N \B"
$PN"62"26;
"CA0_A"
$PN"66"166;
"CA0_B"
$PN"76"165;
"CA1_A"
$PN"211"164;
"CA1_B"
$PN"221"163;
"CA2_A"
$PN"68"162;
"CA2_B"
$PN"78"161;
"CA3_A"
$PN"213"160;
"CA3_B"
$PN"223"159;
"CA4_A"
$PN"70"158;
"CA4_B"
$PN"80"157;
"CA5_A"
$PN"215"156;
"CA5_B"
$PN"225"155;
"CA6_A"
$PN"72"154;
"CA6_B"
$PN"82"153;
"CB6_A"
$PN"203"152;
"CB5_A"
$PN"60"151;
"CB3_A"
$PN"198"150;
"CB2_A"
$PN"196"149;
"CB0_A"
$PN"51"148;
"CB6_B"
$PN"234"147;
"CB5_B"
$PN"91"146;
"CB4_B"
$PN"89"145;
"CB3_B"
$PN"243"144;
"CB2_B"
$PN"241"143;
"CB1_B"
$PN"98"14;
"CB0_B"
$PN"96"28;
"CK_C \B"
$PN"218"142;
"CK_T"
$PN"217"141;
"CS0_A_N"
$PN"64"140;
"CS0_B_N"
$PN"84"139;
"CS1_A_N"
$PN"209"138;
"CS1_B_N"
$PN"229"137;
"DQ30_A"
$PN"192"136;
"DQ29_A"
$PN"49"135;
"DQ28_A"
$PN"47"134;
"DQ27_A"
$PN"187"133;
"DQ26_A"
$PN"185"132;
"DQ25_A"
$PN"42"131;
"DQ24_A"
$PN"40"130;
"DQ23_A"
$PN"183"129;
"DQ22_A"
$PN"181"128;
"DQ21_A"
$PN"38"127;
"DQ20_A"
$PN"36"37;
"DQ19_A"
$PN"176"38;
"DQ18_A"
$PN"174"39;
"DQ17_A"
$PN"31"126;
"DQ16_A"
$PN"29"125;
"DQ15_A"
$PN"172"124;
"DQ14_A"
$PN"170"32;
"DQ13_A"
$PN"27"33;
"DQ12_A"
$PN"25"34;
"DQ11_A"
$PN"165"35;
"DQ10_A"
$PN"163"36;
"DQ9_A"
$PN"20"123;
"DQ8_A"
$PN"18"122;
"DQ7_A"
$PN"161"121;
"DQ6_A"
$PN"159"120;
"DQ5_A"
$PN"16"119;
"DQ4_A"
$PN"14"118;
"DQ3_A"
$PN"154"117;
"DQ2_A"
$PN"152"116;
"DQ1_A"
$PN"9"115;
"DQ0_A"
$PN"7"114;
"DQ31_B"
$PN"287"113;
"DQ30_B"
$PN"285"112;
"DQ29_B"
$PN"142"111;
"DQ28_B"
$PN"140"110;
"DQ27_B"
$PN"280"109;
"DQ26_B"
$PN"278"108;
"DQ25_B"
$PN"135"107;
"DQ24_B"
$PN"133"106;
"DQ23_B"
$PN"276"105;
"DQ22_B"
$PN"274"104;
"DQ21_B"
$PN"131"103;
"DQ20_B"
$PN"129"102;
"DQ19_B"
$PN"269"101;
"DQ18_B"
$PN"267"100;
"DQ17_B"
$PN"124"99;
"DQ16_B"
$PN"122"98;
"DQ15_B"
$PN"265"97;
"DQ14_B"
$PN"263"96;
"DQ13_B"
$PN"120"95;
"DQ12_B"
$PN"118"94;
"DQ11_B"
$PN"258"93;
"DQ10_B"
$PN"256"92;
"DQ9_B"
$PN"113"91;
"DQ8_B"
$PN"111"90;
"DQ7_B"
$PN"254"89;
"DQ6_B"
$PN"252"88;
"DQ5_B"
$PN"109"87;
"DQ4_B"
$PN"107"86;
"DQ3_B"
$PN"247"85;
"DQ2_B"
$PN"245"84;
"DQ1_B"
$PN"102"83;
"DQ0_B"
$PN"100"82;
"HAS"
$PN"148"16;
"HSCL"
$PN"4"20;
"HSDA"
$PN"5"17;
"LBD||RSP_A_N"
$PN"86"31;
"LBS||RSP_B_N"
$PN"87"30;
"PAR_A"
$PN"74"81;
"PAR_B"
$PN"227"80;
"RESET_N \B"
$PN"207"27;
"RFU6"
$PN"232"0;
"RFU5"
$PN"231"0;
"RFU4"
$PN"220"0;
"RFU3"
$PN"150"0;
"RFU2"
$PN"149"0;
"RFU1"
$PN"144"0;
"RFU0"
$PN"2"0;
"VIN_MGMT"
$PN"3"15;
%"TAP"
"1","(-3500,3550)","0","mstr_standard","I220";
;
CDS_LIB"mstr_standard"
BODY_TYPE"PLUMBING"
HDL_TAP"TRUE";
"B \NAC \NWC"12;
"S \NAC"
BN"8"77;
%"TAP"
"1","(-3500,3450)","0","mstr_standard","I221";
;
CDS_LIB"mstr_standard"
BODY_TYPE"PLUMBING"
HDL_TAP"TRUE";
"B \NAC \NWC"12;
"S \NAC"
BN"7"75;
%"TAP"
"1","(-3300,3300)","0","mstr_standard","I222";
;
CDS_LIB"mstr_standard"
BODY_TYPE"PLUMBING"
HDL_TAP"TRUE";
"B \NAC \NWC"13;
"S \NAC"
BN"6"49;
%"TAP"
"1","(-3300,3200)","0","mstr_standard","I223";
;
CDS_LIB"mstr_standard"
BODY_TYPE"PLUMBING"
HDL_TAP"TRUE";
"B \NAC \NWC"13;
"S \NAC"
BN"5"52;
%"TAP"
"1","(-3300,3000)","0","mstr_standard","I224";
;
CDS_LIB"mstr_standard"
BODY_TYPE"PLUMBING"
HDL_TAP"TRUE";
"B \NAC \NWC"13;
"S \NAC"
BN"3"60;
%"TAP"
"1","(-3300,3100)","0","mstr_standard","I225";
;
CDS_LIB"mstr_standard"
BODY_TYPE"PLUMBING"
HDL_TAP"TRUE";
"B \NAC \NWC"13;
"S \NAC"
BN"4"56;
%"TAP"
"1","(-3300,2900)","0","mstr_standard","I226";
;
CDS_LIB"mstr_standard"
BODY_TYPE"PLUMBING"
HDL_TAP"TRUE";
"B \NAC \NWC"13;
"S \NAC"
BN"2"64;
%"TAP"
"1","(-3500,3150)","0","mstr_standard","I227";
;
CDS_LIB"mstr_standard"
BODY_TYPE"PLUMBING"
HDL_TAP"TRUE";
"B \NAC \NWC"12;
"S \NAC"
BN"4"55;
%"TAP"
"1","(-3500,3350)","0","mstr_standard","I228";
;
CDS_LIB"mstr_standard"
BODY_TYPE"PLUMBING"
HDL_TAP"TRUE";
"B \NAC \NWC"12;
"S \NAC"
BN"6"48;
%"TAP"
"1","(-3500,3250)","0","mstr_standard","I229";
;
CDS_LIB"mstr_standard"
BODY_TYPE"PLUMBING"
HDL_TAP"TRUE";
"B \NAC \NWC"12;
"S \NAC"
BN"5"51;
%"TAP"
"1","(-7825,3325)","2","mstr_standard","I23";
;
CDS_LIB"mstr_standard"
BODY_TYPE"PLUMBING"
HDL_TAP"TRUE";
"B \NAC \NWC"6;
"S \NAC"
BN"0"28;
%"TAP"
"1","(-3500,2950)","0","mstr_standard","I230";
;
CDS_LIB"mstr_standard"
BODY_TYPE"PLUMBING"
HDL_TAP"TRUE";
"B \NAC \NWC"12;
"S \NAC"
BN"2"63;
%"TAP"
"1","(-3500,3050)","0","mstr_standard","I231";
;
CDS_LIB"mstr_standard"
BODY_TYPE"PLUMBING"
HDL_TAP"TRUE";
"B \NAC \NWC"12;
"S \NAC"
BN"3"59;
%"TAP"
"1","(-3300,2800)","0","mstr_standard","I232";
;
CDS_LIB"mstr_standard"
BODY_TYPE"PLUMBING"
HDL_TAP"TRUE";
"B \NAC \NWC"13;
"S \NAC"
BN"1"68;
%"TAP"
"1","(-3300,2700)","0","mstr_standard","I233";
;
CDS_LIB"mstr_standard"
BODY_TYPE"PLUMBING"
HDL_TAP"TRUE";
"B \NAC \NWC"13;
"S \NAC"
BN"0"72;
%"TAP"
"1","(-3500,2750)","0","mstr_standard","I234";
;
CDS_LIB"mstr_standard"
BODY_TYPE"PLUMBING"
HDL_TAP"TRUE";
"B \NAC \NWC"12;
"S \NAC"
BN"0"71;
%"TAP"
"1","(-3500,2850)","0","mstr_standard","I235";
;
CDS_LIB"mstr_standard"
BODY_TYPE"PLUMBING"
HDL_TAP"TRUE";
"B \NAC \NWC"12;
"S \NAC"
BN"1"67;
%"SCONN288_DDR506112002KQ"
"2","(-4450,3700)","0","pure_quanta","I236";
;
LOCATION"J33"
$SEC"2"
CDS_SEC"2"
VALUE"SCONN288_DDR506112002KQ"
MATERIAL"IO"
PART_TYPE"SMLF"
CDS_LMAN_SYM_OUTLINE"-600,1150,600,-1150"
NEEDS_NO_SIZE"TRUE"
CDS_LIB"pure_quanta"
PART_NUMBER"DFHST8FS479";
"DQS7_A_C||TDQS7_A_C \B"
$PN"178"79;
"DQS6_A_T||TDQS6_A_T"
$PN"168"78;
"DQS8_B_T||TDQS8_B_T"
$PN"283"77;
"DQS8_B_C||TDQS8_B_C \B"
$PN"282"76;
"DQS7_B_T||TDQS7_B_T"
$PN"272"75;
"DQS0_A_C \B"
$PN"12"74;
"DQS0_A_T"
$PN"11"73;
"DQS0_B_C \B"
$PN"105"72;
"DQS0_B_T"
$PN"104"71;
"DQS1_A_C \B"
$PN"23"70;
"DQS1_A_T"
$PN"22"69;
"DQS1_B_C \B"
$PN"116"68;
"DQS1_B_T"
$PN"115"67;
"DQS2_A_C \B"
$PN"34"66;
"DQS2_A_T"
$PN"33"65;
"DQS2_B_C \B"
$PN"127"64;
"DQS2_B_T"
$PN"126"63;
"DQS3_A_C \B"
$PN"45"62;
"DQS3_A_T"
$PN"44"61;
"DQS3_B_C \B"
$PN"138"60;
"DQS3_B_T"
$PN"137"59;
"DQS4_A_C \B"
$PN"56"58;
"DQS4_A_T"
$PN"55"57;
"DQS4_B_C \B"
$PN"238"56;
"DQS4_B_T"
$PN"239"55;
"DQS5_A_C||TDQS5_A_C||DQS5_A_T||TDQS5_A_T \B"
$PN"156"54;
"DQS5_A_T||TDQS5_A_T"
$PN"157"53;
"DQS5_B_C||TDQS5_B_C \B"
$PN"249"52;
"DQS5_B_T||TDQS5_B_T"
$PN"250"51;
"DQS6_A_C||TDQS6_A_C||DQS6_A_T||TDQS6_A_T \B"
$PN"167"50;
"DQS6_B_C||TDQS6_B_C \B"
$PN"260"49;
"DQS6_B_T||TDQS6_B_T"
$PN"261"48;
"DQS7_A_T||TDQS7_A_T"
$PN"179"47;
"DQS7_B_C||TDQS7_B_C \B"
$PN"271"46;
"DQS8_A_C||TDQS8_A_C \B"
$PN"189"45;
"DQS8_A_T||TDQS8_A_T"
$PN"190"44;
"DQS9_A_C||TDQS9_A_C \B"
$PN"200"43;
"DQS9_A_T||TDQS9_A_T"
$PN"201"42;
"DQS9_B_C||TDQS9_B_C \B"
$PN"94"41;
"DQS9_B_T||TDQS9_B_T||DBI4_B_N"
$PN"93"40;
%"GND"
"1","(-2900,5650)","0","pure_quanta_power","I237";
;
CDS_LIB"pure_quanta_power"
BOM_COST"MEM"
SIZE"1B"
ROOM"MEM_EFGH_DECOUPLING_CAPS"
HDL_POWER"GND";
"A<SIZE-1..0>\NAC"23;
%"Q_CAP"
"1","(-2900,6000)","2","pure_quanta","I238";
;
LOCATION"C518"
$SEC"1"
CDS_SEC"1"
PACK_TYPE"C0805"
VOLTAGE"25V"
VALUE"10UF"
TOLERANCE"10%"
MATERIAL"X6S"
CDS_LIB"pure_quanta"
BOM_COST"MEM"
ROOM""
PART_NUMBER"CH6104KEA00";
"B"
$PN"2"23;
"A"
$PN"1"24;
%"Q_CAP"
"1","(-2325,6000)","2","pure_quanta","I239";
;
LOCATION"C527"
$SEC"1"
CDS_SEC"1"
PACK_TYPE"C0805"
VOLTAGE"25V"
VALUE"10UF"
TOLERANCE"10%"
MATERIAL"X6S"
CDS_LIB"pure_quanta"
BOM_COST"MEM"
ROOM""
PART_NUMBER"CH6104KEA00";
"B"
$PN"2"23;
"A"
$PN"1"24;
%"TAP"
"1","(-7825,3375)","2","mstr_standard","I24";
;
CDS_LIB"mstr_standard"
BODY_TYPE"PLUMBING"
HDL_TAP"TRUE";
"B \NAC \NWC"6;
"S \NAC"
BN"1"14;
%"UNIVERSAL_POWER"
"1","(-2900,6325)","0","pure_quanta_power","I240";
;
HDL_POWER"P12V_MEM_CPU1"
CDS_LIB"pure_quanta_power";
"A"24;
%"Q_RES"
"1","(-7850,2750)","0","pure_quanta","I242";
;
LOCATION"R1585"
$SEC"1"
CDS_SEC"1"
VALUE"49.9"
CDS_LIB"pure_quanta"
MATERIAL"CHIP"
PACK_TYPE"0402LF"
WATTAGE"1/16W"
TOLERANCE"1%"
PART_NUMBER"CS04992FB07";
"B"
$PN"2"20;
"A"
$PN"1"19;
%"Q_RES"
"1","(-8250,2975)","0","pure_quanta","I243";
;
LOCATION"R1704"
$SEC"1"
CDS_SEC"1"
PACK_TYPE"0402LF"
MATERIAL"CHIP"
VALUE"10"
CDS_LIB"pure_quanta"
TOLERANCE"1%"
WATTAGE"1/16W"
PART_NUMBER"CS01002FB07";
"B"
$PN"2"17;
"A"
$PN"1"18;
%"TAP"
"1","(-7825,3425)","2","mstr_standard","I25";
;
CDS_LIB"mstr_standard"
BODY_TYPE"PLUMBING"
HDL_TAP"TRUE";
"B \NAC \NWC"6;
"S \NAC"
BN"2"143;
%"TAP"
"1","(-7825,3475)","2","mstr_standard","I26";
;
CDS_LIB"mstr_standard"
BODY_TYPE"PLUMBING"
HDL_TAP"TRUE";
"B \NAC \NWC"6;
"S \NAC"
BN"3"144;
%"TAP"
"1","(-7825,3525)","2","mstr_standard","I27";
;
CDS_LIB"mstr_standard"
BODY_TYPE"PLUMBING"
HDL_TAP"TRUE";
"B \NAC \NWC"6;
"S \NAC"
BN"4"145;
%"TAP"
"1","(-7825,3625)","2","mstr_standard","I28";
;
CDS_LIB"mstr_standard"
BODY_TYPE"PLUMBING"
HDL_TAP"TRUE";
"B \NAC \NWC"6;
"S \NAC"
BN"6"147;
%"TAP"
"1","(-7825,3575)","2","mstr_standard","I29";
;
CDS_LIB"mstr_standard"
BODY_TYPE"PLUMBING"
HDL_TAP"TRUE";
"B \NAC \NWC"6;
"S \NAC"
BN"5"146;
%"TAP"
"1","(-7825,3675)","2","mstr_standard","I30";
;
CDS_LIB"mstr_standard"
BODY_TYPE"PLUMBING"
HDL_TAP"TRUE";
"B \NAC \NWC"6;
"S \NAC"
BN"7"167;
%"TAP"
"1","(-7825,3775)","2","mstr_standard","I31";
;
CDS_LIB"mstr_standard"
BODY_TYPE"PLUMBING"
HDL_TAP"TRUE";
"B \NAC \NWC"5;
"S \NAC"
BN"0"148;
%"TAP"
"1","(-7825,3825)","2","mstr_standard","I32";
;
CDS_LIB"mstr_standard"
BODY_TYPE"PLUMBING"
HDL_TAP"TRUE";
"B \NAC \NWC"5;
"S \NAC"
BN"1"168;
%"TAP"
"1","(-7825,3875)","2","mstr_standard","I33";
;
CDS_LIB"mstr_standard"
BODY_TYPE"PLUMBING"
HDL_TAP"TRUE";
"B \NAC \NWC"5;
"S \NAC"
BN"2"149;
%"TAP"
"1","(-7825,3925)","2","mstr_standard","I34";
;
CDS_LIB"mstr_standard"
BODY_TYPE"PLUMBING"
HDL_TAP"TRUE";
"B \NAC \NWC"5;
"S \NAC"
BN"3"150;
%"TAP"
"1","(-6125,2325)","0","mstr_standard","I35";
;
CDS_LIB"mstr_standard"
BODY_TYPE"PLUMBING"
HDL_TAP"TRUE";
"B \NAC \NWC"9;
"S \NAC"
BN"0"82;
%"TAP"
"1","(-6125,2375)","0","mstr_standard","I36";
;
CDS_LIB"mstr_standard"
BODY_TYPE"PLUMBING"
HDL_TAP"TRUE";
"B \NAC \NWC"9;
"S \NAC"
BN"1"83;
%"TAP"
"1","(-6125,2425)","0","mstr_standard","I37";
;
CDS_LIB"mstr_standard"
BODY_TYPE"PLUMBING"
HDL_TAP"TRUE";
"B \NAC \NWC"9;
"S \NAC"
BN"2"84;
%"TAP"
"1","(-6125,2475)","0","mstr_standard","I38";
;
CDS_LIB"mstr_standard"
BODY_TYPE"PLUMBING"
HDL_TAP"TRUE";
"B \NAC \NWC"9;
"S \NAC"
BN"3"85;
%"TAP"
"1","(-6125,2525)","0","mstr_standard","I39";
;
CDS_LIB"mstr_standard"
BODY_TYPE"PLUMBING"
HDL_TAP"TRUE";
"B \NAC \NWC"9;
"S \NAC"
BN"4"86;
%"TAP"
"1","(-6125,2575)","0","mstr_standard","I40";
;
CDS_LIB"mstr_standard"
BODY_TYPE"PLUMBING"
HDL_TAP"TRUE";
"B \NAC \NWC"9;
"S \NAC"
BN"5"87;
%"TAP"
"1","(-6125,2625)","0","mstr_standard","I41";
;
CDS_LIB"mstr_standard"
BODY_TYPE"PLUMBING"
HDL_TAP"TRUE";
"B \NAC \NWC"9;
"S \NAC"
BN"6"88;
%"TAP"
"1","(-6125,2675)","0","mstr_standard","I42";
;
CDS_LIB"mstr_standard"
BODY_TYPE"PLUMBING"
HDL_TAP"TRUE";
"B \NAC \NWC"9;
"S \NAC"
BN"7"89;
%"TAP"
"1","(-6125,2725)","0","mstr_standard","I43";
;
CDS_LIB"mstr_standard"
BODY_TYPE"PLUMBING"
HDL_TAP"TRUE";
"B \NAC \NWC"9;
"S \NAC"
BN"8"90;
%"TAP"
"1","(-6125,2775)","0","mstr_standard","I44";
;
CDS_LIB"mstr_standard"
BODY_TYPE"PLUMBING"
HDL_TAP"TRUE";
"B \NAC \NWC"9;
"S \NAC"
BN"9"91;
%"TAP"
"1","(-6125,2825)","0","mstr_standard","I45";
;
CDS_LIB"mstr_standard"
BODY_TYPE"PLUMBING"
HDL_TAP"TRUE";
"B \NAC \NWC"9;
"S \NAC"
BN"10"92;
%"TAP"
"1","(-6125,2875)","0","mstr_standard","I46";
;
CDS_LIB"mstr_standard"
BODY_TYPE"PLUMBING"
HDL_TAP"TRUE";
"B \NAC \NWC"9;
"S \NAC"
BN"11"93;
%"TAP"
"1","(-6125,2925)","0","mstr_standard","I47";
;
CDS_LIB"mstr_standard"
BODY_TYPE"PLUMBING"
HDL_TAP"TRUE";
"B \NAC \NWC"9;
"S \NAC"
BN"12"94;
%"TAP"
"1","(-6125,2975)","0","mstr_standard","I48";
;
CDS_LIB"mstr_standard"
BODY_TYPE"PLUMBING"
HDL_TAP"TRUE";
"B \NAC \NWC"9;
"S \NAC"
BN"13"95;
%"TAP"
"1","(-6125,3025)","0","mstr_standard","I49";
;
CDS_LIB"mstr_standard"
BODY_TYPE"PLUMBING"
HDL_TAP"TRUE";
"B \NAC \NWC"9;
"S \NAC"
BN"14"96;
%"VCC_CORE"
"1","(-8575,3550)","0","mstr_symbols","I5";
;
HDL_POWER"P3V3_AUX"
CDS_LIB"mstr_symbols"
VOLTAGE"3.3"
ROOM"PVCCINFAON_CPU1_CTRL";
"A"15;
%"TAP"
"1","(-6125,3125)","0","mstr_standard","I50";
;
CDS_LIB"mstr_standard"
BODY_TYPE"PLUMBING"
HDL_TAP"TRUE";
"B \NAC \NWC"9;
"S \NAC"
BN"16"98;
%"TAP"
"1","(-6125,3075)","0","mstr_standard","I51";
;
CDS_LIB"mstr_standard"
BODY_TYPE"PLUMBING"
HDL_TAP"TRUE";
"B \NAC \NWC"9;
"S \NAC"
BN"15"97;
%"TAP"
"1","(-6125,3175)","0","mstr_standard","I52";
;
CDS_LIB"mstr_standard"
BODY_TYPE"PLUMBING"
HDL_TAP"TRUE";
"B \NAC \NWC"9;
"S \NAC"
BN"17"99;
%"TAP"
"1","(-6125,3275)","0","mstr_standard","I53";
;
CDS_LIB"mstr_standard"
BODY_TYPE"PLUMBING"
HDL_TAP"TRUE";
"B \NAC \NWC"9;
"S \NAC"
BN"19"101;
%"TAP"
"1","(-6125,3325)","0","mstr_standard","I54";
;
CDS_LIB"mstr_standard"
BODY_TYPE"PLUMBING"
HDL_TAP"TRUE";
"B \NAC \NWC"9;
"S \NAC"
BN"20"102;
%"TAP"
"1","(-6125,3425)","0","mstr_standard","I55";
;
CDS_LIB"mstr_standard"
BODY_TYPE"PLUMBING"
HDL_TAP"TRUE";
"B \NAC \NWC"9;
"S \NAC"
BN"22"104;
%"TAP"
"1","(-6125,3375)","0","mstr_standard","I56";
;
CDS_LIB"mstr_standard"
BODY_TYPE"PLUMBING"
HDL_TAP"TRUE";
"B \NAC \NWC"9;
"S \NAC"
BN"21"103;
%"TAP"
"1","(-6125,3225)","0","mstr_standard","I57";
;
CDS_LIB"mstr_standard"
BODY_TYPE"PLUMBING"
HDL_TAP"TRUE";
"B \NAC \NWC"9;
"S \NAC"
BN"18"100;
%"TAP"
"1","(-6125,3525)","0","mstr_standard","I58";
;
CDS_LIB"mstr_standard"
BODY_TYPE"PLUMBING"
HDL_TAP"TRUE";
"B \NAC \NWC"9;
"S \NAC"
BN"24"106;
%"TAP"
"1","(-6125,3575)","0","mstr_standard","I59";
;
CDS_LIB"mstr_standard"
BODY_TYPE"PLUMBING"
HDL_TAP"TRUE";
"B \NAC \NWC"9;
"S \NAC"
BN"25"107;
%"TAP"
"1","(-6125,3675)","0","mstr_standard","I60";
;
CDS_LIB"mstr_standard"
BODY_TYPE"PLUMBING"
HDL_TAP"TRUE";
"B \NAC \NWC"9;
"S \NAC"
BN"27"109;
%"TAP"
"1","(-6125,3625)","0","mstr_standard","I61";
;
CDS_LIB"mstr_standard"
BODY_TYPE"PLUMBING"
HDL_TAP"TRUE";
"B \NAC \NWC"9;
"S \NAC"
BN"26"108;
%"TAP"
"1","(-6125,3475)","0","mstr_standard","I62";
;
CDS_LIB"mstr_standard"
BODY_TYPE"PLUMBING"
HDL_TAP"TRUE";
"B \NAC \NWC"9;
"S \NAC"
BN"23"105;
%"TAP"
"1","(-6125,3775)","0","mstr_standard","I63";
;
CDS_LIB"mstr_standard"
BODY_TYPE"PLUMBING"
HDL_TAP"TRUE";
"B \NAC \NWC"9;
"S \NAC"
BN"29"111;
%"TAP"
"1","(-6125,3875)","0","mstr_standard","I64";
;
CDS_LIB"mstr_standard"
BODY_TYPE"PLUMBING"
HDL_TAP"TRUE";
"B \NAC \NWC"9;
"S \NAC"
BN"31"113;
%"TAP"
"1","(-6125,3825)","0","mstr_standard","I65";
;
CDS_LIB"mstr_standard"
BODY_TYPE"PLUMBING"
HDL_TAP"TRUE";
"B \NAC \NWC"9;
"S \NAC"
BN"30"112;
%"TAP"
"1","(-6125,3725)","0","mstr_standard","I66";
;
CDS_LIB"mstr_standard"
BODY_TYPE"PLUMBING"
HDL_TAP"TRUE";
"B \NAC \NWC"9;
"S \NAC"
BN"28"110;
%"TAP"
"1","(-7825,3975)","2","mstr_standard","I76";
;
CDS_LIB"mstr_standard"
BODY_TYPE"PLUMBING"
HDL_TAP"TRUE";
"B \NAC \NWC"5;
"S \NAC"
BN"4"169;
%"TAP"
"1","(-7825,4025)","2","mstr_standard","I77";
;
CDS_LIB"mstr_standard"
BODY_TYPE"PLUMBING"
HDL_TAP"TRUE";
"B \NAC \NWC"5;
"S \NAC"
BN"5"151;
%"TAP"
"1","(-7825,4125)","2","mstr_standard","I78";
;
CDS_LIB"mstr_standard"
BODY_TYPE"PLUMBING"
HDL_TAP"TRUE";
"B \NAC \NWC"5;
"S \NAC"
BN"7"170;
%"TAP"
"1","(-7825,4075)","2","mstr_standard","I79";
;
CDS_LIB"mstr_standard"
BODY_TYPE"PLUMBING"
HDL_TAP"TRUE";
"B \NAC \NWC"5;
"S \NAC"
BN"6"152;
%"TAP"
"1","(-7825,4825)","2","mstr_standard","I80";
;
CDS_LIB"mstr_standard"
BODY_TYPE"PLUMBING"
HDL_TAP"TRUE";
"B \NAC \NWC"8;
"S \NAC"
BN"0"165;
%"TAP"
"1","(-7825,4875)","2","mstr_standard","I81";
;
CDS_LIB"mstr_standard"
BODY_TYPE"PLUMBING"
HDL_TAP"TRUE";
"B \NAC \NWC"8;
"S \NAC"
BN"1"163;
%"TAP"
"1","(-7825,4925)","2","mstr_standard","I82";
;
CDS_LIB"mstr_standard"
BODY_TYPE"PLUMBING"
HDL_TAP"TRUE";
"B \NAC \NWC"8;
"S \NAC"
BN"2"161;
%"TAP"
"1","(-7825,5025)","2","mstr_standard","I83";
;
CDS_LIB"mstr_standard"
BODY_TYPE"PLUMBING"
HDL_TAP"TRUE";
"B \NAC \NWC"8;
"S \NAC"
BN"4"157;
%"TAP"
"1","(-7825,4975)","2","mstr_standard","I84";
;
CDS_LIB"mstr_standard"
BODY_TYPE"PLUMBING"
HDL_TAP"TRUE";
"B \NAC \NWC"8;
"S \NAC"
BN"3"159;
%"TAP"
"1","(-7825,5075)","2","mstr_standard","I85";
;
CDS_LIB"mstr_standard"
BODY_TYPE"PLUMBING"
HDL_TAP"TRUE";
"B \NAC \NWC"8;
"S \NAC"
BN"5"155;
%"TAP"
"1","(-7825,5125)","2","mstr_standard","I86";
;
CDS_LIB"mstr_standard"
BODY_TYPE"PLUMBING"
HDL_TAP"TRUE";
"B \NAC \NWC"8;
"S \NAC"
BN"6"153;
%"TAP"
"1","(-7825,5225)","2","mstr_standard","I87";
;
CDS_LIB"mstr_standard"
BODY_TYPE"PLUMBING"
HDL_TAP"TRUE";
"B \NAC \NWC"7;
"S \NAC"
BN"0"166;
%"TAP"
"1","(-7825,5275)","2","mstr_standard","I88";
;
CDS_LIB"mstr_standard"
BODY_TYPE"PLUMBING"
HDL_TAP"TRUE";
"B \NAC \NWC"7;
"S \NAC"
BN"1"164;
%"TAP"
"1","(-7825,5325)","2","mstr_standard","I89";
;
CDS_LIB"mstr_standard"
BODY_TYPE"PLUMBING"
HDL_TAP"TRUE";
"B \NAC \NWC"7;
"S \NAC"
BN"2"162;
%"TAP"
"1","(-7825,5375)","2","mstr_standard","I90";
;
CDS_LIB"mstr_standard"
BODY_TYPE"PLUMBING"
HDL_TAP"TRUE";
"B \NAC \NWC"7;
"S \NAC"
BN"3"160;
%"TAP"
"1","(-7825,5425)","2","mstr_standard","I91";
;
CDS_LIB"mstr_standard"
BODY_TYPE"PLUMBING"
HDL_TAP"TRUE";
"B \NAC \NWC"7;
"S \NAC"
BN"4"158;
%"TAP"
"1","(-7825,5475)","2","mstr_standard","I92";
;
CDS_LIB"mstr_standard"
BODY_TYPE"PLUMBING"
HDL_TAP"TRUE";
"B \NAC \NWC"7;
"S \NAC"
BN"5"156;
%"TAP"
"1","(-7825,5525)","2","mstr_standard","I93";
;
CDS_LIB"mstr_standard"
BODY_TYPE"PLUMBING"
HDL_TAP"TRUE";
"B \NAC \NWC"7;
"S \NAC"
BN"6"154;
%"TAP"
"1","(-6125,3975)","0","mstr_standard","I94";
;
CDS_LIB"mstr_standard"
BODY_TYPE"PLUMBING"
HDL_TAP"TRUE";
"B \NAC \NWC"4;
"S \NAC"
BN"0"114;
%"TAP"
"1","(-6125,4025)","0","mstr_standard","I95";
;
CDS_LIB"mstr_standard"
BODY_TYPE"PLUMBING"
HDL_TAP"TRUE";
"B \NAC \NWC"4;
"S \NAC"
BN"1"115;
%"TAP"
"1","(-6125,4075)","0","mstr_standard","I96";
;
CDS_LIB"mstr_standard"
BODY_TYPE"PLUMBING"
HDL_TAP"TRUE";
"B \NAC \NWC"4;
"S \NAC"
BN"2"116;
%"TAP"
"1","(-6125,4125)","0","mstr_standard","I97";
;
CDS_LIB"mstr_standard"
BODY_TYPE"PLUMBING"
HDL_TAP"TRUE";
"B \NAC \NWC"4;
"S \NAC"
BN"3"117;
%"TAP"
"1","(-6125,4175)","0","mstr_standard","I98";
;
CDS_LIB"mstr_standard"
BODY_TYPE"PLUMBING"
HDL_TAP"TRUE";
"B \NAC \NWC"4;
"S \NAC"
BN"4"118;
%"TAP"
"1","(-6125,4225)","0","mstr_standard","I99";
;
CDS_LIB"mstr_standard"
BODY_TYPE"PLUMBING"
HDL_TAP"TRUE";
"B \NAC \NWC"4;
"S \NAC"
BN"5"119;
END.
